(kicad_pcb
	(version 20260206)
	(generator "pcbnew")
	(generator_version "10.0")
	(general
		(thickness 1.6)
		(legacy_teardrops no)
	)
	(paper "A4")
	(title_block
		(title "01162023_DA0F0TEBIF0_F0T_Expander_BD_F_brd_V02_OCP.brd")
		(comment 1 "Grand Teton / footprint 4451 of 9728 (PEX3), pads 957-1074 of 2397")
	)
	(layers
		(0 "F.Cu" signal "TOP")
		(4 "In1.Cu" signal "GND")
		(6 "In2.Cu" signal "VCC")
		(8 "In3.Cu" signal "VCC1")
		(10 "In4.Cu" signal "GND1")
		(12 "In5.Cu" signal "IN1")
		(14 "In6.Cu" signal "GND2")
		(16 "In7.Cu" signal "IN2")
		(18 "In8.Cu" signal "GND3")
		(20 "In9.Cu" signal "IN3")
		(22 "In10.Cu" signal "GND4")
		(24 "In11.Cu" signal "IN4")
		(26 "In12.Cu" signal "GND5")
		(28 "In13.Cu" signal "IN5")
		(30 "In14.Cu" signal "GND6")
		(32 "In15.Cu" signal "IN6")
		(34 "In16.Cu" signal "GND7")
		(2 "B.Cu" signal "BOTTOM")
		(9 "F.Adhes" user "F.Adhesive")
		(11 "B.Adhes" user "B.Adhesive")
		(13 "F.Paste" user "Package Geometry/Pastemask Top")
		(15 "B.Paste" user "Package Geometry/Pastemask Bottom")
		(5 "F.SilkS" user "Ref Des/Silkscreen Top")
		(7 "B.SilkS" user "Ref Des/Silkscreen Bottom")
		(1 "F.Mask" user "Board Geometry/Soldermask Top")
		(3 "B.Mask" user "Board Geometry/Soldermask Bottom")
		(17 "Dwgs.User" user "User.Drawings")
		(19 "Cmts.User" user "User.Comments")
		(21 "Eco1.User" user "User.Eco1")
		(23 "Eco2.User" user "User.Eco2")
		(25 "Edge.Cuts" user "Board Geometry/Outline")
		(27 "Margin" user)
		(31 "F.CrtYd" user "Package Geometry/Place Bound Top")
		(29 "B.CrtYd" user "Package Geometry/Place Bound Bottom")
		(35 "F.Fab" user "Ref Des/Assembly Top")
		(33 "B.Fab" user "Ref Des/Assembly Bottom")
	)
	(footprint ""
		(layer "F.Cu")
		(at 407.949908 -295.89984)
		(property "Reference" "PEX3"
			(at -3.358642 35.5727 0)
			(unlocked yes)
			(layer "F.SilkS")
			(effects
				(font
					(size 2.032 1.524)
					(thickness 0.1524)
				)
				(justify left)
			)
		)
		(property "Value" ""
			(at 0 0 0)
			(layer "F.Fab")
			(effects
				(font
					(size 1.27 1.27)
				)
			)
		)
		(duplicate_pad_numbers_are_jumpers no)
		(pad "AW28" smd circle
			(at 2.84988 13.299948)
			(size 0.4572 0.4572)
			(layers "F.Cu" "F.Mask" "F.Paste")
			(net "PEX3_MODE_SEL4")
		)
		(pad "AW29" smd circle
			(at 3.800094 13.299948)
			(size 0.4572 0.4572)
			(layers "F.Cu" "F.Mask" "F.Paste")
			(net "PEX3_MODE_SEL8")
		)
		(pad "AW30" smd circle
			(at 4.750054 13.299948)
			(size 0.4572 0.4572)
			(layers "F.Cu" "F.Mask" "F.Paste")
			(net "PEX3_DBG_MODE2")
		)
		(pad "AW31" smd circle
			(at 5.700014 13.299948)
			(size 0.4572 0.4572)
			(layers "F.Cu" "F.Mask" "F.Paste")
			(net "PEX3_MODE_SEL11")
		)
		(pad "AW32" smd circle
			(at 6.649974 13.299948)
			(size 0.4572 0.4572)
			(layers "F.Cu" "F.Mask" "F.Paste")
			(net "PEX3_MODE_SEL12")
		)
		(pad "AW33" smd circle
			(at 7.599934 13.299948)
			(size 0.4572 0.4572)
			(layers "F.Cu" "F.Mask" "F.Paste")
			(net "Net_5440")
		)
		(pad "AW34" smd circle
			(at 8.549894 13.299948)
			(size 0.4572 0.4572)
			(layers "F.Cu" "F.Mask" "F.Paste")
			(net "PEX3_DBG_MODE4")
		)
		(pad "AW35" smd circle
			(at 9.500108 13.299948)
			(size 0.4572 0.4572)
			(layers "F.Cu" "F.Mask" "F.Paste")
			(net "Net_5419")
		)
		(pad "AW36" smd circle
			(at 10.450068 13.299948)
			(size 0.4572 0.4572)
			(layers "F.Cu" "F.Mask" "F.Paste")
			(net "Net_5443")
		)
		(pad "AW37" smd circle
			(at 11.400028 13.299948)
			(size 0.4572 0.4572)
			(layers "F.Cu" "F.Mask" "F.Paste")
			(net "Net_5447")
		)
		(pad "AW38" smd circle
			(at 12.349988 13.299948)
			(size 0.4572 0.4572)
			(layers "F.Cu" "F.Mask" "F.Paste")
			(net "PEX3_MODE_SEL1")
		)
		(pad "AW39" smd circle
			(at 13.299948 13.299948)
			(size 0.4572 0.4572)
			(layers "F.Cu" "F.Mask" "F.Paste")
			(net "Net_5414")
		)
		(pad "AW40" smd circle
			(at 14.249908 13.299948)
			(size 0.4572 0.4572)
			(layers "F.Cu" "F.Mask" "F.Paste")
			(net "GND")
		)
		(pad "AW41" smd circle
			(at 15.200122 13.299948)
			(size 0.4572 0.4572)
			(layers "F.Cu" "F.Mask" "F.Paste")
			(net "GND")
		)
		(pad "AW42" smd circle
			(at 16.150082 13.299948)
			(size 0.4572 0.4572)
			(layers "F.Cu" "F.Mask" "F.Paste")
			(net "GND")
		)
		(pad "AW43" smd circle
			(at 17.100042 13.299948)
			(size 0.4572 0.4572)
			(layers "F.Cu" "F.Mask" "F.Paste")
			(net "P5E_PEX3_STN0_TX_DP<6>")
		)
		(pad "AW44" smd circle
			(at 18.050002 13.299948)
			(size 0.4572 0.4572)
			(layers "F.Cu" "F.Mask" "F.Paste")
			(net "P5E_PEX3_STN0_TX_DN<6>")
		)
		(pad "AW45" smd circle
			(at 18.999962 13.299948)
			(size 0.4572 0.4572)
			(layers "F.Cu" "F.Mask" "F.Paste")
			(net "GND")
		)
		(pad "AW46" smd circle
			(at 19.949922 13.299948)
			(size 0.4572 0.4572)
			(layers "F.Cu" "F.Mask" "F.Paste")
			(net "P5E_PEX3_STN0_RX_DP<6>")
		)
		(pad "AW47" smd circle
			(at 20.899882 13.299948)
			(size 0.4572 0.4572)
			(layers "F.Cu" "F.Mask" "F.Paste")
			(net "P5E_PEX3_STN0_RX_DN<6>")
		)
		(pad "AW48" smd circle
			(at 21.850096 13.299948)
			(size 0.4572 0.4572)
			(layers "F.Cu" "F.Mask" "F.Paste")
			(net "GND")
		)
		(pad "AW49" smd circle
			(at 22.800056 13.299948)
			(size 0.4572 0.4572)
			(layers "F.Cu" "F.Mask" "F.Paste")
			(net "GND")
		)
		(pad "AY1" smd circle
			(at -22.800056 14.249908)
			(size 0.4572 0.4572)
			(layers "F.Cu" "F.Mask" "F.Paste")
			(net "Net_1408")
		)
		(pad "AY2" smd circle
			(at -21.850096 14.249908)
			(size 0.4572 0.4572)
			(layers "F.Cu" "F.Mask" "F.Paste")
			(net "Net_1435")
		)
		(pad "AY3" smd circle
			(at -20.899882 14.249908)
			(size 0.4572 0.4572)
			(layers "F.Cu" "F.Mask" "F.Paste")
			(net "GND")
		)
		(pad "AY4" smd circle
			(at -19.949922 14.249908)
			(size 0.4572 0.4572)
			(layers "F.Cu" "F.Mask" "F.Paste")
			(net "GND")
		)
		(pad "AY5" smd circle
			(at -18.999962 14.249908)
			(size 0.4572 0.4572)
			(layers "F.Cu" "F.Mask" "F.Paste")
			(net "GND")
		)
		(pad "AY6" smd circle
			(at -18.050002 14.249908)
			(size 0.4572 0.4572)
			(layers "F.Cu" "F.Mask" "F.Paste")
			(net "GND")
		)
		(pad "AY7" smd circle
			(at -17.100042 14.249908)
			(size 0.4572 0.4572)
			(layers "F.Cu" "F.Mask" "F.Paste")
			(net "GND")
		)
		(pad "AY8" smd circle
			(at -16.150082 14.249908)
			(size 0.4572 0.4572)
			(layers "F.Cu" "F.Mask" "F.Paste")
			(net "GND")
		)
		(pad "AY9" smd circle
			(at -15.200122 14.249908)
			(size 0.4572 0.4572)
			(layers "F.Cu" "F.Mask" "F.Paste")
			(net "GND")
		)
		(pad "AY10" smd circle
			(at -14.249908 14.249908)
			(size 0.4572 0.4572)
			(layers "F.Cu" "F.Mask" "F.Paste")
			(net "GND")
		)
		(pad "AY11" smd circle
			(at -13.299948 14.249908)
			(size 0.4572 0.4572)
			(layers "F.Cu" "F.Mask" "F.Paste")
			(net "GND")
		)
		(pad "AY12" smd circle
			(at -12.349988 14.249908)
			(size 0.4572 0.4572)
			(layers "F.Cu" "F.Mask" "F.Paste")
			(net "GND")
		)
		(pad "AY13" smd circle
			(at -11.400028 14.249908)
			(size 0.4572 0.4572)
			(layers "F.Cu" "F.Mask" "F.Paste")
			(net "GND")
		)
		(pad "AY14" smd circle
			(at -10.450068 14.249908)
			(size 0.4572 0.4572)
			(layers "F.Cu" "F.Mask" "F.Paste")
			(net "GND")
		)
		(pad "AY15" smd circle
			(at -9.500108 14.249908)
			(size 0.4572 0.4572)
			(layers "F.Cu" "F.Mask" "F.Paste")
			(net "GND")
		)
		(pad "AY16" smd circle
			(at -8.549894 14.249908)
			(size 0.4572 0.4572)
			(layers "F.Cu" "F.Mask" "F.Paste")
			(net "GND")
		)
		(pad "AY17" smd circle
			(at -7.599934 14.249908)
			(size 0.4572 0.4572)
			(layers "F.Cu" "F.Mask" "F.Paste")
			(net "GND")
		)
		(pad "AY18" smd circle
			(at -6.649974 14.249908)
			(size 0.4572 0.4572)
			(layers "F.Cu" "F.Mask" "F.Paste")
			(net "GND")
		)
		(pad "AY19" smd circle
			(at -5.700014 14.249908)
			(size 0.4572 0.4572)
			(layers "F.Cu" "F.Mask" "F.Paste")
			(net "GND")
		)
		(pad "AY20" smd circle
			(at -4.750054 14.249908)
			(size 0.4572 0.4572)
			(layers "F.Cu" "F.Mask" "F.Paste")
			(net "GND")
		)
		(pad "AY21" smd circle
			(at -3.800094 14.249908)
			(size 0.4572 0.4572)
			(layers "F.Cu" "F.Mask" "F.Paste")
			(net "GND")
		)
		(pad "AY22" smd circle
			(at -2.84988 14.249908)
			(size 0.4572 0.4572)
			(layers "F.Cu" "F.Mask" "F.Paste")
			(net "GND")
		)
		(pad "AY23" smd circle
			(at -1.89992 14.249908)
			(size 0.4572 0.4572)
			(layers "F.Cu" "F.Mask" "F.Paste")
			(net "GND")
		)
		(pad "AY24" smd circle
			(at -0.94996 14.249908)
			(size 0.4572 0.4572)
			(layers "F.Cu" "F.Mask" "F.Paste")
			(net "GND")
		)
		(pad "AY25" smd circle
			(at 0 14.249908)
			(size 0.4572 0.4572)
			(layers "F.Cu" "F.Mask" "F.Paste")
			(net "GND")
		)
		(pad "AY26" smd circle
			(at 0.94996 14.249908)
			(size 0.4572 0.4572)
			(layers "F.Cu" "F.Mask" "F.Paste")
			(net "GND")
		)
		(pad "AY27" smd circle
			(at 1.89992 14.249908)
			(size 0.4572 0.4572)
			(layers "F.Cu" "F.Mask" "F.Paste")
			(net "GND")
		)
		(pad "AY28" smd circle
			(at 2.84988 14.249908)
			(size 0.4572 0.4572)
			(layers "F.Cu" "F.Mask" "F.Paste")
			(net "GND")
		)
		(pad "AY29" smd circle
			(at 3.800094 14.249908)
			(size 0.4572 0.4572)
			(layers "F.Cu" "F.Mask" "F.Paste")
			(net "GND")
		)
		(pad "AY30" smd circle
			(at 4.750054 14.249908)
			(size 0.4572 0.4572)
			(layers "F.Cu" "F.Mask" "F.Paste")
			(net "GND")
		)
		(pad "AY31" smd circle
			(at 5.700014 14.249908)
			(size 0.4572 0.4572)
			(layers "F.Cu" "F.Mask" "F.Paste")
			(net "GND")
		)
		(pad "AY32" smd circle
			(at 6.649974 14.249908)
			(size 0.4572 0.4572)
			(layers "F.Cu" "F.Mask" "F.Paste")
			(net "GND")
		)
		(pad "AY33" smd circle
			(at 7.599934 14.249908)
			(size 0.4572 0.4572)
			(layers "F.Cu" "F.Mask" "F.Paste")
			(net "GND")
		)
		(pad "AY34" smd circle
			(at 8.549894 14.249908)
			(size 0.4572 0.4572)
			(layers "F.Cu" "F.Mask" "F.Paste")
			(net "GND")
		)
		(pad "AY35" smd circle
			(at 9.500108 14.249908)
			(size 0.4572 0.4572)
			(layers "F.Cu" "F.Mask" "F.Paste")
			(net "GND")
		)
		(pad "AY36" smd circle
			(at 10.450068 14.249908)
			(size 0.4572 0.4572)
			(layers "F.Cu" "F.Mask" "F.Paste")
			(net "GND")
		)
		(pad "AY37" smd circle
			(at 11.400028 14.249908)
			(size 0.4572 0.4572)
			(layers "F.Cu" "F.Mask" "F.Paste")
			(net "GND")
		)
		(pad "AY38" smd circle
			(at 12.349988 14.249908)
			(size 0.4572 0.4572)
			(layers "F.Cu" "F.Mask" "F.Paste")
			(net "GND")
		)
		(pad "AY39" smd circle
			(at 13.299948 14.249908)
			(size 0.4572 0.4572)
			(layers "F.Cu" "F.Mask" "F.Paste")
			(net "GND")
		)
		(pad "AY40" smd circle
			(at 14.249908 14.249908)
			(size 0.4572 0.4572)
			(layers "F.Cu" "F.Mask" "F.Paste")
			(net "GND")
		)
		(pad "AY41" smd circle
			(at 15.200122 14.249908)
			(size 0.4572 0.4572)
			(layers "F.Cu" "F.Mask" "F.Paste")
			(net "GND")
		)
		(pad "AY42" smd circle
			(at 16.150082 14.249908)
			(size 0.4572 0.4572)
			(layers "F.Cu" "F.Mask" "F.Paste")
			(net "GND")
		)
		(pad "AY43" smd circle
			(at 17.100042 14.249908)
			(size 0.4572 0.4572)
			(layers "F.Cu" "F.Mask" "F.Paste")
			(net "GND")
		)
		(pad "AY44" smd circle
			(at 18.050002 14.249908)
			(size 0.4572 0.4572)
			(layers "F.Cu" "F.Mask" "F.Paste")
			(net "GND")
		)
		(pad "AY45" smd circle
			(at 18.999962 14.249908)
			(size 0.4572 0.4572)
			(layers "F.Cu" "F.Mask" "F.Paste")
			(net "GND")
		)
		(pad "AY46" smd circle
			(at 19.949922 14.249908)
			(size 0.4572 0.4572)
			(layers "F.Cu" "F.Mask" "F.Paste")
			(net "GND")
		)
		(pad "AY47" smd circle
			(at 20.899882 14.249908)
			(size 0.4572 0.4572)
			(layers "F.Cu" "F.Mask" "F.Paste")
			(net "GND")
		)
		(pad "AY48" smd circle
			(at 21.850096 14.249908)
			(size 0.4572 0.4572)
			(layers "F.Cu" "F.Mask" "F.Paste")
			(net "P5E_PEX3_STN0_RX_DP<7>")
		)
		(pad "AY49" smd circle
			(at 22.800056 14.249908)
			(size 0.4572 0.4572)
			(layers "F.Cu" "F.Mask" "F.Paste")
			(net "P5E_PEX3_STN0_RX_DN<7>")
		)
		(pad "B1" smd circle
			(at -22.800056 -21.850096)
			(size 0.4572 0.4572)
			(layers "F.Cu" "F.Mask" "F.Paste")
			(net "GND")
		)
		(pad "B2" smd circle
			(at -21.850096 -21.850096)
			(size 0.4572 0.4572)
			(layers "F.Cu" "F.Mask" "F.Paste")
			(net "GND")
		)
		(pad "B3" smd circle
			(at -20.899882 -21.850096)
			(size 0.4572 0.4572)
			(layers "F.Cu" "F.Mask" "F.Paste")
			(net "P5E_PEX3_STN7_RX_DP<123>")
		)
		(pad "B4" smd circle
			(at -19.949922 -21.850096)
			(size 0.4572 0.4572)
			(layers "F.Cu" "F.Mask" "F.Paste")
			(net "GND")
		)
		(pad "B5" smd circle
			(at -18.999962 -21.850096)
			(size 0.4572 0.4572)
			(layers "F.Cu" "F.Mask" "F.Paste")
			(net "P5E_PEX3_STN7_RX_DP<125>")
		)
		(pad "B6" smd circle
			(at -18.050002 -21.850096)
			(size 0.4572 0.4572)
			(layers "F.Cu" "F.Mask" "F.Paste")
			(net "GND")
		)
		(pad "B7" smd circle
			(at -17.100042 -21.850096)
			(size 0.4572 0.4572)
			(layers "F.Cu" "F.Mask" "F.Paste")
			(net "P5E_PEX3_STN7_RX_DP<127>")
		)
		(pad "B8" smd circle
			(at -16.150082 -21.850096)
			(size 0.4572 0.4572)
			(layers "F.Cu" "F.Mask" "F.Paste")
			(net "GND")
		)
		(pad "B9" smd circle
			(at -15.200122 -21.850096)
			(size 0.4572 0.4572)
			(layers "F.Cu" "F.Mask" "F.Paste")
			(net "P5E_PEX3_STN6_RX_DP<110>")
		)
		(pad "B10" smd circle
			(at -14.249908 -21.850096)
			(size 0.4572 0.4572)
			(layers "F.Cu" "F.Mask" "F.Paste")
			(net "GND")
		)
		(pad "B11" smd circle
			(at -13.299948 -21.850096)
			(size 0.4572 0.4572)
			(layers "F.Cu" "F.Mask" "F.Paste")
			(net "P5E_PEX3_STN6_RX_DP<108>")
		)
		(pad "B12" smd circle
			(at -12.349988 -21.850096)
			(size 0.4572 0.4572)
			(layers "F.Cu" "F.Mask" "F.Paste")
			(net "GND")
		)
		(pad "B13" smd circle
			(at -11.400028 -21.850096)
			(size 0.4572 0.4572)
			(layers "F.Cu" "F.Mask" "F.Paste")
			(net "P5E_PEX3_STN6_RX_DP<106>")
		)
		(pad "B14" smd circle
			(at -10.450068 -21.850096)
			(size 0.4572 0.4572)
			(layers "F.Cu" "F.Mask" "F.Paste")
			(net "GND")
		)
		(pad "B15" smd circle
			(at -9.500108 -21.850096)
			(size 0.4572 0.4572)
			(layers "F.Cu" "F.Mask" "F.Paste")
			(net "P5E_PEX3_STN6_RX_DP<104>")
		)
		(pad "B16" smd circle
			(at -8.549894 -21.850096)
			(size 0.4572 0.4572)
			(layers "F.Cu" "F.Mask" "F.Paste")
			(net "GND")
		)
		(pad "B17" smd circle
			(at -7.599934 -21.850096)
			(size 0.4572 0.4572)
			(layers "F.Cu" "F.Mask" "F.Paste")
			(net "P5E_PEX3_STN6_RX_DP<102>")
		)
		(pad "B18" smd circle
			(at -6.649974 -21.850096)
			(size 0.4572 0.4572)
			(layers "F.Cu" "F.Mask" "F.Paste")
			(net "GND")
		)
		(pad "B19" smd circle
			(at -5.700014 -21.850096)
			(size 0.4572 0.4572)
			(layers "F.Cu" "F.Mask" "F.Paste")
			(net "P5E_PEX3_STN6_RX_DP<100>")
		)
		(pad "B20" smd circle
			(at -4.750054 -21.850096)
			(size 0.4572 0.4572)
			(layers "F.Cu" "F.Mask" "F.Paste")
			(net "GND")
		)
		(pad "B21" smd circle
			(at -3.800094 -21.850096)
			(size 0.4572 0.4572)
			(layers "F.Cu" "F.Mask" "F.Paste")
			(net "P5E_PEX3_STN6_RX_DP<98>")
		)
		(pad "B22" smd circle
			(at -2.84988 -21.850096)
			(size 0.4572 0.4572)
			(layers "F.Cu" "F.Mask" "F.Paste")
			(net "GND")
		)
		(pad "B23" smd circle
			(at -1.89992 -21.850096)
			(size 0.4572 0.4572)
			(layers "F.Cu" "F.Mask" "F.Paste")
			(net "P5E_PEX3_STN6_RX_DP<96>")
		)
		(pad "B24" smd circle
			(at -0.94996 -21.850096)
			(size 0.4572 0.4572)
			(layers "F.Cu" "F.Mask" "F.Paste")
			(net "GND")
		)
		(pad "B25" smd circle
			(at 0 -21.850096)
			(size 0.4572 0.4572)
			(layers "F.Cu" "F.Mask" "F.Paste")
			(net "P5E_PEX3_STN5_RX_DP<81>")
		)
		(pad "B26" smd circle
			(at 0.94996 -21.850096)
			(size 0.4572 0.4572)
			(layers "F.Cu" "F.Mask" "F.Paste")
			(net "GND")
		)
		(pad "B27" smd circle
			(at 1.89992 -21.850096)
			(size 0.4572 0.4572)
			(layers "F.Cu" "F.Mask" "F.Paste")
			(net "P5E_PEX3_STN5_RX_DP<83>")
		)
		(pad "B28" smd circle
			(at 2.84988 -21.850096)
			(size 0.4572 0.4572)
			(layers "F.Cu" "F.Mask" "F.Paste")
			(net "GND")
		)
		(pad "B29" smd circle
			(at 3.800094 -21.850096)
			(size 0.4572 0.4572)
			(layers "F.Cu" "F.Mask" "F.Paste")
			(net "P5E_PEX3_STN5_RX_DP<85>")
		)
		(pad "B30" smd circle
			(at 4.750054 -21.850096)
			(size 0.4572 0.4572)
			(layers "F.Cu" "F.Mask" "F.Paste")
			(net "GND")
		)
		(pad "B31" smd circle
			(at 5.700014 -21.850096)
			(size 0.4572 0.4572)
			(layers "F.Cu" "F.Mask" "F.Paste")
			(net "P5E_PEX3_STN5_RX_DP<87>")
		)
		(pad "B32" smd circle
			(at 6.649974 -21.850096)
			(size 0.4572 0.4572)
			(layers "F.Cu" "F.Mask" "F.Paste")
			(net "GND")
		)
		(pad "B33" smd circle
			(at 7.599934 -21.850096)
			(size 0.4572 0.4572)
			(layers "F.Cu" "F.Mask" "F.Paste")
			(net "P5E_PEX3_STN5_RX_DP<89>")
		)
		(pad "B34" smd circle
			(at 8.549894 -21.850096)
			(size 0.4572 0.4572)
			(layers "F.Cu" "F.Mask" "F.Paste")
			(net "GND")
		)
		(pad "B35" smd circle
			(at 9.500108 -21.850096)
			(size 0.4572 0.4572)
			(layers "F.Cu" "F.Mask" "F.Paste")
			(net "P5E_PEX3_STN5_RX_DP<91>")
		)
		(pad "B36" smd circle
			(at 10.450068 -21.850096)
			(size 0.4572 0.4572)
			(layers "F.Cu" "F.Mask" "F.Paste")
			(net "GND")
		)
		(pad "B37" smd circle
			(at 11.400028 -21.850096)
			(size 0.4572 0.4572)
			(layers "F.Cu" "F.Mask" "F.Paste")
			(net "P5E_PEX3_STN5_RX_DP<93>")
		)
		(pad "B38" smd circle
			(at 12.349988 -21.850096)
			(size 0.4572 0.4572)
			(layers "F.Cu" "F.Mask" "F.Paste")
			(net "GND")
		)
		(pad "B39" smd circle
			(at 13.299948 -21.850096)
			(size 0.4572 0.4572)
			(layers "F.Cu" "F.Mask" "F.Paste")
			(net "P5E_PEX3_STN5_RX_DP<95>")
		)
		(pad "B40" smd circle
			(at 14.249908 -21.850096)
			(size 0.4572 0.4572)
			(layers "F.Cu" "F.Mask" "F.Paste")
			(net "GND")
		)
		(pad "B41" smd circle
			(at 15.200122 -21.850096)
			(size 0.4572 0.4572)
			(layers "F.Cu" "F.Mask" "F.Paste")
			(net "P5E_PEX3_STN4_RX_DP<78>")
		)
		(pad "B42" smd circle
			(at 16.150082 -21.850096)
			(size 0.4572 0.4572)
			(layers "F.Cu" "F.Mask" "F.Paste")
			(net "GND")
		)
		(pad "B43" smd circle
			(at 17.100042 -21.850096)
			(size 0.4572 0.4572)
			(layers "F.Cu" "F.Mask" "F.Paste")
			(net "P5E_PEX3_STN4_RX_DP<76>")
		)
		(pad "B44" smd circle
			(at 18.050002 -21.850096)
			(size 0.4572 0.4572)
			(layers "F.Cu" "F.Mask" "F.Paste")
			(net "GND")
		)
		(pad "B45" smd circle
			(at 18.999962 -21.850096)
			(size 0.4572 0.4572)
			(layers "F.Cu" "F.Mask" "F.Paste")
			(net "P5E_PEX3_STN4_RX_DP<74>")
		)
		(pad "B46" smd circle
			(at 19.949922 -21.850096)
			(size 0.4572 0.4572)
			(layers "F.Cu" "F.Mask" "F.Paste")
			(net "GND")
		)
		(pad "B47" smd circle
			(at 20.899882 -21.850096)
			(size 0.4572 0.4572)
			(layers "F.Cu" "F.Mask" "F.Paste")
			(net "P5E_PEX3_STN4_RX_DP<72>")
		)
	)
)
